# T6G (Grand Teton) — schematic netlist excerpt (pin names and nets, part order shuffled) for the footprints in the layout excerpt that follows; sources: Cadence DE-HDL packaged netlist, KiCad conversion of 04192023_DAF0TMB3IC0_F0TG_MB_C_brd_V02_OCP.brd

D91  Q_LED  IC  pkg SMLF  page 254 : A = LED_PWRGD_P1V8_AUX ; C = LED_PWRGD_P1V8_AUX_D
C884  Q_CAP_DIFFBUS  DIFF BUS_0.22UF 6.3V 20% X6S  pkg C0201  page 64 : \1\ = P5E_CPU0_P3_TX_C_DN<8> ; \2\ = P5E_CPU0_P3_TX_DN<8>
PC157  Q_CAP  560PF 50V 10% EMPTY  pkg C0402  page 203 : A = SW_PVDDCR_CPU1_P0_SW5 ; B = SW_PVDDCR_CPU1_P0_SW5_RC

(kicad_pcb
	(version 20260206)
	(generator "pcbnew")
	(generator_version "10.0")
	(general
		(thickness 1.6)
		(legacy_teardrops no)
	)
	(paper "A4")
	(title_block
		(title "04192023_DAF0TMB3IC0_F0TG_MB_C_brd_V02_OCP.brd")
		(comment 1 "Grand Teton / footprints 4308-4310 of 8354")
	)
	(layers
		(0 "F.Cu" signal "TOP")
		(4 "In1.Cu" signal "GND")
		(6 "In2.Cu" signal "IN1")
		(8 "In3.Cu" signal "GND1")
		(10 "In4.Cu" signal "IN2")
		(12 "In5.Cu" signal "GND2")
		(14 "In6.Cu" signal "IN3")
		(16 "In7.Cu" signal "GND3")
		(18 "In8.Cu" signal "VCC")
		(20 "In9.Cu" signal "VCC1")
		(22 "In10.Cu" signal "GND4")
		(24 "In11.Cu" signal "IN4")
		(26 "In12.Cu" signal "GND5")
		(28 "In13.Cu" signal "IN5")
		(30 "In14.Cu" signal "GND6")
		(32 "In15.Cu" signal "IN6")
		(34 "In16.Cu" signal "GND7")
		(2 "B.Cu" signal "BOTTOM")
		(9 "F.Adhes" user "F.Adhesive")
		(11 "B.Adhes" user "B.Adhesive")
		(13 "F.Paste" user "Package Geometry/Pastemask Top")
		(15 "B.Paste" user "Package Geometry/Pastemask Bottom")
		(5 "F.SilkS" user "Ref Des/Silkscreen Top")
		(7 "B.SilkS" user "Ref Des/Silkscreen Bottom")
		(1 "F.Mask" user "Board Geometry/Soldermask Top")
		(3 "B.Mask" user "Board Geometry/Soldermask Bottom")
		(17 "Dwgs.User" user "User.Drawings")
		(19 "Cmts.User" user "User.Comments")
		(21 "Eco1.User" user "User.Eco1")
		(23 "Eco2.User" user "User.Eco2")
		(25 "Edge.Cuts" user "Board Geometry/Outline")
		(27 "Margin" user)
		(31 "F.CrtYd" user "Package Geometry/Place Bound Top")
		(29 "B.CrtYd" user "Package Geometry/Place Bound Bottom")
		(35 "F.Fab" user "Ref Des/Assembly Top")
		(33 "B.Fab" user "Ref Des/Assembly Bottom")
	)
	(footprint ""
		(layer "F.Cu")
		(at 339.696298 -332.020164 180)
		(property "Reference" "PC157"
			(at 0 0 180)
			(layer "F.SilkS")
			(hide yes)
			(effects
				(font
					(size 1.27 1.27)
				)
			)
		)
		(property "Value" ""
			(at 0 0 180)
			(layer "F.Fab")
			(effects
				(font
					(size 1.27 1.27)
				)
			)
		)
		(duplicate_pad_numbers_are_jumpers no)
		(fp_line
			(start 0.7874 0.4064)
			(end -0.7874 0.4064)
			(stroke
				(width 0.1524)
				(type default)
			)
			(layer "F.SilkS")
		)
		(fp_line
			(start 0.7874 -0.4064)
			(end 0.7874 0.4064)
			(stroke
				(width 0.1524)
				(type default)
			)
			(layer "F.SilkS")
		)
		(fp_line
			(start -0.7874 0.4064)
			(end -0.7874 -0.4064)
			(stroke
				(width 0.1524)
				(type default)
			)
			(layer "F.SilkS")
		)
		(fp_line
			(start -0.7874 -0.4064)
			(end 0.7874 -0.4064)
			(stroke
				(width 0.1524)
				(type default)
			)
			(layer "F.SilkS")
		)
		(fp_line
			(start 0.67945 0.3048)
			(end 0.120396 0.3048)
			(stroke
				(width 0.1)
				(type default)
			)
			(layer "F.Fab")
		)
		(fp_line
			(start 0.67945 -0.3048)
			(end 0.67945 0.3048)
			(stroke
				(width 0.1)
				(type default)
			)
			(layer "F.Fab")
		)
		(fp_line
			(start 0.12065 -0.2794)
			(end 0.12065 -0.3048)
			(stroke
				(width 0.1)
				(type default)
			)
			(layer "F.Fab")
		)
		(fp_line
			(start 0.12065 -0.3048)
			(end 0.67945 -0.3048)
			(stroke
				(width 0.1)
				(type default)
			)
			(layer "F.Fab")
		)
		(fp_line
			(start 0.120396 0.3048)
			(end 0.120396 0.2794)
			(stroke
				(width 0.1)
				(type default)
			)
			(layer "F.Fab")
		)
		(fp_line
			(start 0.120396 0.2794)
			(end -0.12065 0.2794)
			(stroke
				(width 0.1)
				(type default)
			)
			(layer "F.Fab")
		)
		(fp_line
			(start -0.12065 0.3048)
			(end -0.67945 0.3048)
			(stroke
				(width 0.1)
				(type default)
			)
			(layer "F.Fab")
		)
		(fp_line
			(start -0.12065 0.2794)
			(end -0.12065 0.3048)
			(stroke
				(width 0.1)
				(type default)
			)
			(layer "F.Fab")
		)
		(fp_line
			(start -0.12065 -0.2794)
			(end 0.12065 -0.2794)
			(stroke
				(width 0.1)
				(type default)
			)
			(layer "F.Fab")
		)
		(fp_line
			(start -0.12065 -0.305054)
			(end -0.12065 -0.2794)
			(stroke
				(width 0.1)
				(type default)
			)
			(layer "F.Fab")
		)
		(fp_line
			(start -0.67945 0.3048)
			(end -0.67945 -0.305054)
			(stroke
				(width 0.1)
				(type default)
			)
			(layer "F.Fab")
		)
		(fp_line
			(start -0.67945 -0.305054)
			(end -0.12065 -0.305054)
			(stroke
				(width 0.1)
				(type default)
			)
			(layer "F.Fab")
		)
		(pad "1" smd circle
			(at -0.40005 0 180)
			(size 0 0)
			(layers "F.Cu" "F.Mask" "F.Paste")
			(net "SW_PVDDCR_CPU1_P0_SW5")
		)
		(pad "2" smd circle
			(at 0.40005 0 180)
			(size 0 0)
			(layers "F.Cu" "F.Mask" "F.Paste")
			(net "SW_PVDDCR_CPU1_P0_SW5_RC")
		)
	)
	(footprint ""
		(layer "F.Cu")
		(at 380.618492 -381.41783 -90)
		(property "Reference" "C884"
			(at 0 0 270)
			(layer "F.SilkS")
			(hide yes)
			(effects
				(font
					(size 1.27 1.27)
				)
			)
		)
		(property "Value" ""
			(at 0 0 270)
			(layer "F.Fab")
			(effects
				(font
					(size 1.27 1.27)
				)
			)
		)
		(duplicate_pad_numbers_are_jumpers no)
		(fp_line
			(start -0.299974 0.150114)
			(end -0.299974 -0.150114)
			(stroke
				(width 0.1)
				(type default)
			)
			(layer "F.Fab")
		)
		(fp_line
			(start 0.299974 0.150114)
			(end -0.299974 0.150114)
			(stroke
				(width 0.1)
				(type default)
			)
			(layer "F.Fab")
		)
		(fp_line
			(start -0.299974 -0.150114)
			(end 0.299974 -0.150114)
			(stroke
				(width 0.1)
				(type default)
			)
			(layer "F.Fab")
		)
		(fp_line
			(start 0.299974 -0.150114)
			(end 0.299974 0.150114)
			(stroke
				(width 0.1)
				(type default)
			)
			(layer "F.Fab")
		)
		(pad "1" smd rect
			(at -0.2667 0 270)
			(size 0.3048 0.381)
			(layers "F.Cu" "F.Mask" "F.Paste")
			(net "P5E_CPU0_P3_TX_C_DN<8>")
		)
		(pad "2" smd rect
			(at 0.2667 0 270)
			(size 0.3048 0.381)
			(layers "F.Cu" "F.Mask" "F.Paste")
			(net "P5E_CPU0_P3_TX_DN<8>")
		)
	)
	(footprint ""
		(layer "F.Cu")
		(at 318.539876 -70.098412 90)
		(property "Reference" "D91"
			(at -3.934714 -0.691642 90)
			(unlocked yes)
			(layer "F.SilkS")
			(effects
				(font
					(size 0.7874 0.5842)
					(thickness 0.1524)
				)
				(justify left)
			)
		)
		(property "Value" ""
			(at 0 0 90)
			(layer "F.Fab")
			(effects
				(font
					(size 1.27 1.27)
				)
			)
		)
		(duplicate_pad_numbers_are_jumpers no)
		(fp_line
			(start 1.16078 -0.4826)
			(end 1.16078 0.4826)
			(stroke
				(width 0.1524)
				(type default)
			)
			(layer "F.SilkS")
		)
		(fp_line
			(start 1.03378 -0.4826)
			(end 1.03378 0.4826)
			(stroke
				(width 0.1524)
				(type default)
			)
			(layer "F.SilkS")
		)
		(fp_line
			(start 0.90678 -0.4826)
			(end 0.90678 0.4826)
			(stroke
				(width 0.1524)
				(type default)
			)
			(layer "F.SilkS")
		)
		(fp_line
			(start -0.64008 -0.4826)
			(end 1.16078 -0.4826)
			(stroke
				(width 0.1524)
				(type default)
			)
			(layer "F.SilkS")
		)
		(fp_line
			(start -0.79248 -0.4826)
			(end 1.03378 -0.4826)
			(stroke
				(width 0.1524)
				(type default)
			)
			(layer "F.SilkS")
		)
		(fp_line
			(start -0.89408 -0.4826)
			(end 0.90678 -0.4826)
			(stroke
				(width 0.1524)
				(type default)
			)
			(layer "F.SilkS")
		)
		(fp_line
			(start 1.16078 0.4826)
			(end -0.64008 0.4826)
			(stroke
				(width 0.1524)
				(type default)
			)
			(layer "F.SilkS")
		)
		(fp_line
			(start 1.03378 0.4826)
			(end -0.79248 0.4826)
			(stroke
				(width 0.1524)
				(type default)
			)
			(layer "F.SilkS")
		)
		(fp_line
			(start 0.90678 0.4826)
			(end -0.90678 0.4826)
			(stroke
				(width 0.1524)
				(type default)
			)
			(layer "F.SilkS")
		)
		(fp_line
			(start -0.90678 0.4826)
			(end -0.90678 -0.4699)
			(stroke
				(width 0.1524)
				(type default)
			)
			(layer "F.SilkS")
		)
		(fp_line
			(start 0.499872 -0.249936)
			(end 0.499872 0.249936)
			(stroke
				(width 0.1)
				(type default)
			)
			(layer "F.Fab")
		)
		(fp_line
			(start -0.499872 -0.249936)
			(end 0.499872 -0.249936)
			(stroke
				(width 0.1)
				(type default)
			)
			(layer "F.Fab")
		)
		(fp_line
			(start 0.499872 0.249936)
			(end -0.499872 0.249936)
			(stroke
				(width 0.1)
				(type default)
			)
			(layer "F.Fab")
		)
		(fp_line
			(start -0.499872 0.249936)
			(end -0.499872 -0.249936)
			(stroke
				(width 0.1)
				(type default)
			)
			(layer "F.Fab")
		)
		(pad "A" smd rect
			(at -0.47498 0 90)
			(size 0.6096 0.7112)
			(layers "F.Cu" "F.Mask" "F.Paste")
			(net "LED_PWRGD_P1V8_AUX")
		)
		(pad "C" smd rect
			(at 0.47498 0 90)
			(size 0.6096 0.7112)
			(layers "F.Cu" "F.Mask" "F.Paste")
			(net "LED_PWRGD_P1V8_AUX_D")
		)
	)
)
